# Lightning_PDPB_EQL.xlsx — CLK_1027 (si-constraints)
|  |  | Group | Pin | NET1 | NET2 | Length (NET1) | <1mils match (NET1) | Length (NET2) | <1mils match (NET2) | Unnecessary trace | Total Length | <1mils Total Length match |
|  |  | Card Edge CONN-J17 | A3 | PE_100M_CLK1_C_p | PE_100M_CLK1_p | 442.79 | OK | 14558.9 | OK |  | 15001.69 | OK |
|  |  |  | A2 | PE_100M_CLK1_C_n | PE_100M_CLK1_n | 442.66 |  | 14558.13 |  |  | 15000.789999999999 |  |
|  |  |  | A78 | PE_100M_CLK4_C_p | PE_100M_CLK4_p | 251.28 | OK | 4009.89 | OK |  | 4261.17 | OK |
|  |  |  | A79 | PE_100M_CLK4_C_n | PE_100M_CLK4_n | 251.18 |  | 4009.4 |  |  | 4260.58 |  |
| DPB SPEC |  |  | B2 | PE_100M_CLK2_C_p | PE_100M_CLK2_p | 388.25 | OK | 10303.299999999999 | OK |  | 10691.55 | OK |
| CLK max length | 16inch |  | B3 | PE_100M_CLK2_C_n | PE_100M_CLK2_n | 388.91 |  | 10303.459999999999 |  |  | 10692.369999999999 |  |
| +/- match (Segment) NET1 | 1mil |  | B76 | PE_100M_CLK3_C_p | PE_100M_CLK3_p | 1310.1199999999999 | OK | 7707.7 | OK |  | 9017.82 | OK |
| +/- match (Segment) NET2 | 1mil |  | B77 | PE_100M_CLK3_C_n | PE_100M_CLK3_n | 1310.73 |  | 7707.67 |  |  | 9018.4 |  |
|  |  | CLK Buffer1 | EU1.17 | PE_CLK_100M_DR10_2_R_P | PE_CLK100M_dr10_2_p | 243.56 | OK | 3677.01 | OK |  | 3920.57 | OK |
|  |  |  | EU1.18 | PE_CLK_100M_DR10_2_R_N | PE_CLK100M_dr10_2_n | 243.2 |  | 3677.1 |  |  | 3920.2999999999997 |  |
|  |  |  | EU1.21 | PE_CLK_100M_DR10_1_R_P | PE_CLK100M_dr10_1_p | 183.04 | OK | 4096.16 | OK |  | 4279.2 | OK |
|  |  |  | EU1.22 | PE_CLK_100M_DR10_1_R_N | PE_CLK100M_dr10_1_n | 183.06 |  | 4095.23 |  |  | 4278.29 |  |
|  |  |  | EU1.42 | PE_CLK_100M_DR0_2_R_P | PE_CLK100M_dr0_2_p | 172.55 | OK | 6519.83 | OK |  | 6692.38 | OK |
|  |  |  | EU1.43 | PE_CLK_100M_DR0_2_R_N | PE_CLK100M_dr0_2_n | 172.57 |  | 6519.18 |  |  | 6691.75 |  |
|  |  |  | EU1.46 | PE_CLK_100M_DR0_1_R_P | PE_CLK100M_dr0_1_p | 231.09 | OK | 5342.74 | OK |  | 5573.83 | OK |
|  |  |  | EU1.47 | PE_CLK_100M_DR0_1_R_N | PE_CLK100M_dr0_1_n | 231.09 |  | 5342.75 |  |  | 5573.84 |  |
|  |  |  | EU1.59 | PE_CLK_100M_DR5_2_R_P | PE_CLK100M_dr5_2_p | 183.06 | OK | 2886.98 | OK |  | 3070.04 | OK |
|  |  |  | EU1.60 | PE_CLK_100M_DR5_2_R_N | PE_CLK100M_dr5_2_n | 183.05 |  | 2887.91 |  |  | 3070.96 |  |
|  |  |  | EU1.63 | PE_CLK_100M_DR5_1_R_P | PE_CLK100M_dr5_1_p | 238.57 | OK | 2777.05 | OK |  | 3015.6200000000003 | OK |
|  |  |  | EU1.64 | PE_CLK_100M_DR5_1_R_N | PE_CLK100M_dr5_1_n | 238.59 |  | 2776.13 |  |  | 3014.7200000000003 |  |
|  |  | CLK Buffer2 | EU2.26 | PE_CLK_100M_DR2_2_R_P | PE_CLK100M_dr2_2_p | 172.55 | OK | 7376.67 | OK |  | 7549.22 | OK |
|  |  |  | EU2.27 | PE_CLK_100M_DR2_2_R_N | PE_CLK100M_dr2_2_n | 172.56 |  | 7376.49 |  |  | 7549.05 |  |
|  |  |  | EU2.30 | PE_CLK_100M_DR2_1_R_P | PE_CLK100M_dr2_1_p | 232.13 | OK | 5815.88 | OK |  | 6048.01 | OK |
|  |  |  | EU2.31 | PE_CLK_100M_DR2_1_R_N | PE_CLK100M_dr2_1_n | 232.14 |  | 5816.82 |  |  | 6048.96 |  |
|  |  |  | EU2.42 | PE_CLK_100M_DR1_2_R_P | PE_CLK100M_dr1_2_p | 172.58 | OK | 6885.11 | OK |  | 7057.69 | OK |
|  |  |  | EU2.43 | PE_CLK_100M_DR1_2_R_N | PE_CLK100M_dr1_2_n | 172.56 |  | 6885.78 |  |  | 7058.34 |  |
|  |  |  | EU2.46 | PE_CLK_100M_DR1_1_R_P | PE_CLK100M_dr1_1_p | 229.78 | OK | 5603.73 | OK |  | 5833.5099999999993 | OK |
|  |  |  | EU2.47 | PE_CLK_100M_DR1_1_R_N | PE_CLK100M_dr1_1_n | 229.78 |  | 5603.73 |  |  | 5833.5099999999993 |  |
|  |  |  | EU2.50 | PE_CLK_100M_DR6_2_R_P | PE_CLK100M_dr6_2_p | 232.02 | OK | 3656.81 | OK |  | 3888.83 | OK |
|  |  |  | EU2.51 | PE_CLK_100M_DR6_2_R_N | PE_CLK100M_dr6_2_n | 232.01 |  | 3656.9 |  |  | 3888.91 |  |
|  |  |  | EU2.54 | PE_CLK_100M_DR6_1_R_P | PE_CLK100M_dr6_1_p | 172.56 | OK | 3403.66 | OK |  | 3576.22 | OK |
|  |  |  | EU2.55 | PE_CLK_100M_DR6_1_R_N | PE_CLK100M_dr6_1_n | 172.55 |  | 3403.55 |  |  | 3576.1000000000004 |  |
|  |  |  | EU2.59 | PE_CLK_100M_DR11_2_R_P | PE_CLK100M_dr11_2_p | 188.33 | OK | 3692.56 | OK |  | 3880.89 | OK |
|  |  |  | EU2.60 | PE_CLK_100M_DR11_2_R_N | PE_CLK100M_dr11_2_n | 188.33 |  | 3692.85 |  |  | 3881.18 |  |
|  |  |  | EU2.63 | PE_CLK_100M_DR11_1_R_P | PE_CLK100M_dr11_1_p | 240.11 | OK | 3525.6 | OK |  | 3765.71 | OK |
|  |  |  | EU2.64 | PE_CLK_100M_DR11_1_R_N | PE_CLK100M_dr11_1_n | 239.87 |  | 3526.55 |  |  | 3766.42 |  |
|  |  | CLK Buffer3 | EU3.26 | PE_CLK_100M_DR4_2_R_P | PE_CLK100M_dr4_2_p | 165.81 | OK | 9636.91 | OK |  | 9802.7199999999993 | OK |
|  |  |  | EU3.27 | PE_CLK_100M_DR4_2_R_N | PE_CLK100M_dr4_2_n | 165.83 |  | 9636.5300000000007 |  |  | 9802.36 |  |
|  |  |  | EU3.30 | PE_CLK_100M_DR4_1_R_P | PE_CLK100M_dr4_1_p | 175.16 | OK | 8072.26 | OK |  | 8247.42 | OK |
|  |  |  | EU3.31 | PE_CLK_100M_DR4_1_R_N | PE_CLK100M_dr4_1_n | 174.18 |  | 8072.76 |  |  | 8246.94 |  |
|  |  |  | EU3.34 | PE_CLK_100M_DR3_2_R_P | PE_CLK100M_dr3_2_p | 223.76 | OK | 7846.84 | OK |  | 8070.6 | OK |
|  |  |  | EU3.35 | PE_CLK_100M_DR3_2_R_N | PE_CLK100M_dr3_2_n | 223.75 |  | 7846.2 |  |  | 8069.95 |  |
|  |  |  | EU3.38 | PE_CLK_100M_DR3_1_R_P | PE_CLK100M_dr3_1_p | 172.56 | OK | 6664.8 | OK |  | 6837.3600000000006 | OK |
|  |  |  | EU3.39 | PE_CLK_100M_DR3_1_R_N | PE_CLK100M_dr3_1_n | 173.39 |  | 6664.81 |  |  | 6838.2000000000007 |  |
|  |  |  | EU3.50 | PE_CLK_100M_DR7_2_R_P | PE_CLK100M_dr7_2_p | 223.76 | OK | 3522.9 | OK |  | 3746.66 | OK |
|  |  |  | EU3.51 | PE_CLK_100M_DR7_2_R_N | PE_CLK100M_dr7_2_n | 223.75 |  | 3523 |  |  | 3746.75 |  |
|  |  |  | EU3.54 | PE_CLK_100M_DR7_1_R_P | PE_CLK100M_dr7_1_p | 172.56 | OK | 3255.75 | OK |  | 3428.31 | OK |
|  |  |  | EU3.55 | PE_CLK_100M_DR7_1_R_N | PE_CLK100M_dr7_1_n | 172.55 |  | 3255.64 |  |  | 3428.19 |  |
|  |  |  | EU3.59 | PE_CLK_100M_DR12_2_R_P | PE_CLK100M_dr12_2_p | 183.06 | OK | 3553.44 | OK |  | 3736.5 | OK |
|  |  |  | EU3.60 | PE_CLK_100M_DR12_2_R_N | PE_CLK100M_dr12_2_n | 183.05 |  | 3553.73 |  |  | 3736.78 |  |
|  |  |  | EU3.63 | PE_CLK_100M_DR12_1_R_P | PE_CLK100M_dr12_1_p | 247.14 | OK | 3161.3 | OK |  | 3408.44 | OK |
|  |  |  | EU3.64 | PE_CLK_100M_DR12_1_R_N | PE_CLK100M_dr12_1_n | 247.34 |  | 3161.41 |  |  | 3408.75 |  |
|  |  | CLK Buffer4 | EU4.17 | PE_CLK_100M_DR9_2_R_P | PE_CLK100M_dr9_2_p | 246.4 | OK | 2811.28 | OK |  | 3057.6800000000003 | OK |
|  |  |  | EU4.18 | PE_CLK_100M_DR9_2_R_N | PE_CLK100M_dr9_2_n | 246.54 |  | 2810.35 |  |  | 3056.89 |  |
|  |  |  | EU4.21 | PE_CLK_100M_DR9_1_R_P | PE_CLK100M_dr9_1_p | 183.04 | OK | 3476.01 | OK |  | 3659.05 | OK |
|  |  |  | EU4.22 | PE_CLK_100M_DR9_1_R_N | PE_CLK100M_dr9_1_n | 183.06 |  | 3475.73 |  |  | 3658.79 |  |
|  |  |  | EU4.26 | PE_CLK_100M_DR14_2_R_P | PE_CLK100M_dr14_2_p | 172.55 | OK | 4758.97 | OK |  | 4931.5200000000004 | OK |
|  |  |  | EU4.27 | PE_CLK_100M_DR14_2_R_N | PE_CLK100M_dr14_2_n | 172.57 |  | 4758.8599999999997 |  |  | 4931.4299999999994 |  |
|  |  |  | EU4.30 | PE_CLK_100M_DR14_1_R_P | PE_CLK100M_dr14_1_p | 229.2 | OK | 5256.84 | OK |  | 5486.04 | OK |
|  |  |  | EU4.31 | PE_CLK_100M_DR14_1_R_N | PE_CLK100M_dr14_1_n | 229.2 |  | 5256.75 |  |  | 5485.95 |  |
|  |  |  | EU4.50 | PE_CLK_100M_DR8_2_R_P | PE_CLK100M_dr8_2_p | 223.76 | OK | 3618.87 | OK |  | 3842.63 | OK |
|  |  |  | EU4.51 | PE_CLK_100M_DR8_2_R_N | PE_CLK100M_dr8_2_n | 223.75 |  | 3618.98 |  |  | 3842.73 |  |
|  |  |  | EU4.54 | PE_CLK_100M_DR8_1_R_P | PE_CLK100M_dr8_1_p | 172.56 | OK | 3434.25 | OK |  | 3606.81 | OK |
|  |  |  | EU4.55 | PE_CLK_100M_DR8_1_R_N | PE_CLK100M_dr8_1_n | 172.55 |  | 3434.16 |  |  | 3606.71 |  |
|  |  |  | EU4.59 | PE_CLK_100M_DR13_2_R_P | PE_CLK100M_dr13_2_p | 183.06 | OK | 3653.94 | OK |  | 3837 | OK |
|  |  |  | EU4.60 | PE_CLK_100M_DR13_2_R_N | PE_CLK100M_dr13_2_n | 183.05 |  | 3654.04 |  |  | 3837.09 |  |
|  |  |  | EU4.63 | PE_CLK_100M_DR13_1_R_P | PE_CLK100M_dr13_1_p | 246.55 | OK | 3477.96 | OK |  | 3724.51 | OK |
|  |  |  | EU4.64 | PE_CLK_100M_DR13_1_R_N | PE_CLK100M_dr13_1_n | 246.41 |  | 3477.9 |  |  | 3724.31 |  |
